(kicad_pcb
	(version 20260206)
	(generator "pcbnew")
	(generator_version "10.0")
	(general
		(thickness 1.6)
		(legacy_teardrops no)
	)
	(paper "A4")
	(title_block
		(title "01162023_DA0F0TEBIF0_F0T_Expander_BD_F_brd_V02_OCP.brd")
		(comment 1 "Grand Teton / footprints 6397-6402 of 9728")
	)
	(layers
		(0 "F.Cu" signal "TOP")
		(4 "In1.Cu" signal "GND")
		(6 "In2.Cu" signal "VCC")
		(8 "In3.Cu" signal "VCC1")
		(10 "In4.Cu" signal "GND1")
		(12 "In5.Cu" signal "IN1")
		(14 "In6.Cu" signal "GND2")
		(16 "In7.Cu" signal "IN2")
		(18 "In8.Cu" signal "GND3")
		(20 "In9.Cu" signal "IN3")
		(22 "In10.Cu" signal "GND4")
		(24 "In11.Cu" signal "IN4")
		(26 "In12.Cu" signal "GND5")
		(28 "In13.Cu" signal "IN5")
		(30 "In14.Cu" signal "GND6")
		(32 "In15.Cu" signal "IN6")
		(34 "In16.Cu" signal "GND7")
		(2 "B.Cu" signal "BOTTOM")
		(9 "F.Adhes" user "F.Adhesive")
		(11 "B.Adhes" user "B.Adhesive")
		(13 "F.Paste" user "Package Geometry/Pastemask Top")
		(15 "B.Paste" user "Package Geometry/Pastemask Bottom")
		(5 "F.SilkS" user "Ref Des/Silkscreen Top")
		(7 "B.SilkS" user "Ref Des/Silkscreen Bottom")
		(1 "F.Mask" user "Board Geometry/Soldermask Top")
		(3 "B.Mask" user "Board Geometry/Soldermask Bottom")
		(17 "Dwgs.User" user "User.Drawings")
		(19 "Cmts.User" user "User.Comments")
		(21 "Eco1.User" user "User.Eco1")
		(23 "Eco2.User" user "User.Eco2")
		(25 "Edge.Cuts" user "Board Geometry/Outline")
		(27 "Margin" user)
		(31 "F.CrtYd" user "Package Geometry/Place Bound Top")
		(29 "B.CrtYd" user "Package Geometry/Place Bound Bottom")
		(35 "F.Fab" user "Ref Des/Assembly Top")
		(33 "B.Fab" user "Ref Des/Assembly Bottom")
	)
	(footprint ""
		(layer "F.Cu")
		(at 136.445244 -90.099642 180)
		(property "Reference" "R1580"
			(at 0 0 180)
			(layer "F.SilkS")
			(hide yes)
			(effects
				(font
					(size 1.27 1.27)
				)
			)
		)
		(property "Value" ""
			(at 0 0 180)
			(layer "F.Fab")
			(effects
				(font
					(size 1.27 1.27)
				)
			)
		)
		(duplicate_pad_numbers_are_jumpers no)
		(fp_line
			(start 0.7874 0.4064)
			(end -0.7874 0.4064)
			(stroke
				(width 0.1524)
				(type default)
			)
			(layer "F.SilkS")
		)
		(fp_line
			(start 0.7874 -0.4064)
			(end 0.7874 0.4064)
			(stroke
				(width 0.1524)
				(type default)
			)
			(layer "F.SilkS")
		)
		(fp_line
			(start -0.7874 0.4064)
			(end -0.7874 -0.4064)
			(stroke
				(width 0.1524)
				(type default)
			)
			(layer "F.SilkS")
		)
		(fp_line
			(start -0.7874 -0.4064)
			(end 0.7874 -0.4064)
			(stroke
				(width 0.1524)
				(type default)
			)
			(layer "F.SilkS")
		)
		(fp_line
			(start 0.67945 0.3048)
			(end 0.120396 0.3048)
			(stroke
				(width 0.1)
				(type default)
			)
			(layer "F.Fab")
		)
		(fp_line
			(start 0.67945 -0.3048)
			(end 0.67945 0.3048)
			(stroke
				(width 0.1)
				(type default)
			)
			(layer "F.Fab")
		)
		(fp_line
			(start 0.12065 -0.2794)
			(end 0.12065 -0.3048)
			(stroke
				(width 0.1)
				(type default)
			)
			(layer "F.Fab")
		)
		(fp_line
			(start 0.12065 -0.3048)
			(end 0.67945 -0.3048)
			(stroke
				(width 0.1)
				(type default)
			)
			(layer "F.Fab")
		)
		(fp_line
			(start 0.120396 0.3048)
			(end 0.120396 0.2794)
			(stroke
				(width 0.1)
				(type default)
			)
			(layer "F.Fab")
		)
		(fp_line
			(start 0.120396 0.2794)
			(end -0.12065 0.2794)
			(stroke
				(width 0.1)
				(type default)
			)
			(layer "F.Fab")
		)
		(fp_line
			(start -0.12065 0.3048)
			(end -0.67945 0.3048)
			(stroke
				(width 0.1)
				(type default)
			)
			(layer "F.Fab")
		)
		(fp_line
			(start -0.12065 0.2794)
			(end -0.12065 0.3048)
			(stroke
				(width 0.1)
				(type default)
			)
			(layer "F.Fab")
		)
		(fp_line
			(start -0.12065 -0.2794)
			(end 0.12065 -0.2794)
			(stroke
				(width 0.1)
				(type default)
			)
			(layer "F.Fab")
		)
		(fp_line
			(start -0.12065 -0.305054)
			(end -0.12065 -0.2794)
			(stroke
				(width 0.1)
				(type default)
			)
			(layer "F.Fab")
		)
		(fp_line
			(start -0.67945 0.3048)
			(end -0.67945 -0.305054)
			(stroke
				(width 0.1)
				(type default)
			)
			(layer "F.Fab")
		)
		(fp_line
			(start -0.67945 -0.305054)
			(end -0.12065 -0.305054)
			(stroke
				(width 0.1)
				(type default)
			)
			(layer "F.Fab")
		)
		(pad "1" smd circle
			(at -0.40005 0 180)
			(size 0 0)
			(layers "F.Cu" "F.Mask" "F.Paste")
			(net "SMB_BIC_I2C9_MUX0_SSD5_R_SDA")
		)
		(pad "2" smd circle
			(at 0.40005 0 180)
			(size 0 0)
			(layers "F.Cu" "F.Mask" "F.Paste")
			(net "SMB_BIC_I2C9_MUX0_SSD5_SDA")
		)
	)
	(footprint ""
		(layer "F.Cu")
		(at 30.153356 -291.390832)
		(property "Reference" "L92"
			(at 0 0 0)
			(layer "F.SilkS")
			(hide yes)
			(effects
				(font
					(size 1.27 1.27)
				)
			)
		)
		(property "Value" ""
			(at 0 0 0)
			(layer "F.Fab")
			(effects
				(font
					(size 1.27 1.27)
				)
			)
		)
		(duplicate_pad_numbers_are_jumpers no)
		(fp_line
			(start -1.63576 -0.8128)
			(end -1.63576 0.8128)
			(stroke
				(width 0.1524)
				(type default)
			)
			(layer "F.SilkS")
		)
		(fp_line
			(start -1.63576 -0.8128)
			(end 1.63576 -0.8128)
			(stroke
				(width 0.1524)
				(type default)
			)
			(layer "F.SilkS")
		)
		(fp_line
			(start 1.63576 -0.8128)
			(end 1.63576 0.8128)
			(stroke
				(width 0.1524)
				(type default)
			)
			(layer "F.SilkS")
		)
		(fp_line
			(start 1.63576 0.8128)
			(end -1.63576 0.8128)
			(stroke
				(width 0.1524)
				(type default)
			)
			(layer "F.SilkS")
		)
		(fp_line
			(start -1.56083 -0.738632)
			(end -1.56083 0.7366)
			(stroke
				(width 0.1)
				(type default)
			)
			(layer "F.Fab")
		)
		(fp_line
			(start -1.56083 0.7366)
			(end -1.524 0.7366)
			(stroke
				(width 0.1)
				(type default)
			)
			(layer "F.Fab")
		)
		(fp_line
			(start -1.524 0.7366)
			(end 1.524 0.7366)
			(stroke
				(width 0.1)
				(type default)
			)
			(layer "F.Fab")
		)
		(fp_line
			(start 1.524 0.7366)
			(end 1.560576 0.7366)
			(stroke
				(width 0.1)
				(type default)
			)
			(layer "F.Fab")
		)
		(fp_line
			(start 1.560576 -0.738632)
			(end -1.56083 -0.738632)
			(stroke
				(width 0.1)
				(type default)
			)
			(layer "F.Fab")
		)
		(fp_line
			(start 1.560576 0.7366)
			(end 1.560576 -0.738632)
			(stroke
				(width 0.1)
				(type default)
			)
			(layer "F.Fab")
		)
		(pad "1" smd rect
			(at -0.94996 0 180)
			(size 1.1176 1.3716)
			(layers "F.Cu" "F.Mask" "F.Paste")
			(net "P1V8_PLL0_PEX0")
		)
		(pad "2" smd rect
			(at 0.94996 0 180)
			(size 1.1176 1.3716)
			(layers "F.Cu" "F.Mask" "F.Paste")
			(net "PCEPLL4_VDDA18_PEX0")
		)
	)
	(footprint ""
		(layer "F.Cu")
		(at 21.255736 -152.71115 90)
		(property "Reference" "R685"
			(at 0 0 90)
			(layer "F.SilkS")
			(hide yes)
			(effects
				(font
					(size 1.27 1.27)
				)
			)
		)
		(property "Value" ""
			(at 0 0 90)
			(layer "F.Fab")
			(effects
				(font
					(size 1.27 1.27)
				)
			)
		)
		(duplicate_pad_numbers_are_jumpers no)
		(fp_line
			(start 0.7874 -0.4064)
			(end 0.7874 0.4064)
			(stroke
				(width 0.1524)
				(type default)
			)
			(layer "F.SilkS")
		)
		(fp_line
			(start -0.7874 -0.4064)
			(end 0.7874 -0.4064)
			(stroke
				(width 0.1524)
				(type default)
			)
			(layer "F.SilkS")
		)
		(fp_line
			(start 0.7874 0.4064)
			(end -0.7874 0.4064)
			(stroke
				(width 0.1524)
				(type default)
			)
			(layer "F.SilkS")
		)
		(fp_line
			(start -0.7874 0.4064)
			(end -0.7874 -0.4064)
			(stroke
				(width 0.1524)
				(type default)
			)
			(layer "F.SilkS")
		)
		(fp_line
			(start -0.12065 -0.305054)
			(end -0.12065 -0.2794)
			(stroke
				(width 0.1)
				(type default)
			)
			(layer "F.Fab")
		)
		(fp_line
			(start -0.67945 -0.305054)
			(end -0.12065 -0.305054)
			(stroke
				(width 0.1)
				(type default)
			)
			(layer "F.Fab")
		)
		(fp_line
			(start 0.67945 -0.3048)
			(end 0.67945 0.3048)
			(stroke
				(width 0.1)
				(type default)
			)
			(layer "F.Fab")
		)
		(fp_line
			(start 0.12065 -0.3048)
			(end 0.67945 -0.3048)
			(stroke
				(width 0.1)
				(type default)
			)
			(layer "F.Fab")
		)
		(fp_line
			(start 0.12065 -0.2794)
			(end 0.12065 -0.3048)
			(stroke
				(width 0.1)
				(type default)
			)
			(layer "F.Fab")
		)
		(fp_line
			(start -0.12065 -0.2794)
			(end 0.12065 -0.2794)
			(stroke
				(width 0.1)
				(type default)
			)
			(layer "F.Fab")
		)
		(fp_line
			(start 0.120396 0.2794)
			(end -0.12065 0.2794)
			(stroke
				(width 0.1)
				(type default)
			)
			(layer "F.Fab")
		)
		(fp_line
			(start -0.12065 0.2794)
			(end -0.12065 0.3048)
			(stroke
				(width 0.1)
				(type default)
			)
			(layer "F.Fab")
		)
		(fp_line
			(start 0.67945 0.3048)
			(end 0.120396 0.3048)
			(stroke
				(width 0.1)
				(type default)
			)
			(layer "F.Fab")
		)
		(fp_line
			(start 0.120396 0.3048)
			(end 0.120396 0.2794)
			(stroke
				(width 0.1)
				(type default)
			)
			(layer "F.Fab")
		)
		(fp_line
			(start -0.12065 0.3048)
			(end -0.67945 0.3048)
			(stroke
				(width 0.1)
				(type default)
			)
			(layer "F.Fab")
		)
		(fp_line
			(start -0.67945 0.3048)
			(end -0.67945 -0.305054)
			(stroke
				(width 0.1)
				(type default)
			)
			(layer "F.Fab")
		)
		(pad "1" smd circle
			(at -0.40005 0 90)
			(size 0 0)
			(layers "F.Cu" "F.Mask" "F.Paste")
			(net "NIC0_ADC_A1")
		)
		(pad "2" smd circle
			(at 0.40005 0 90)
			(size 0 0)
			(layers "F.Cu" "F.Mask" "F.Paste")
			(net "GND")
		)
	)
	(footprint ""
		(layer "F.Cu")
		(at 334.518 -205.232 -90)
		(property "Reference" "R4117"
			(at 0 0 270)
			(layer "F.SilkS")
			(hide yes)
			(effects
				(font
					(size 1.27 1.27)
				)
			)
		)
		(property "Value" ""
			(at 0 0 270)
			(layer "F.Fab")
			(effects
				(font
					(size 1.27 1.27)
				)
			)
		)
		(duplicate_pad_numbers_are_jumpers no)
		(fp_line
			(start -0.7874 0.4064)
			(end -0.7874 -0.4064)
			(stroke
				(width 0.1524)
				(type default)
			)
			(layer "F.SilkS")
		)
		(fp_line
			(start 0.7874 0.4064)
			(end -0.7874 0.4064)
			(stroke
				(width 0.1524)
				(type default)
			)
			(layer "F.SilkS")
		)
		(fp_line
			(start -0.7874 -0.4064)
			(end 0.7874 -0.4064)
			(stroke
				(width 0.1524)
				(type default)
			)
			(layer "F.SilkS")
		)
		(fp_line
			(start 0.7874 -0.4064)
			(end 0.7874 0.4064)
			(stroke
				(width 0.1524)
				(type default)
			)
			(layer "F.SilkS")
		)
		(fp_line
			(start -0.67945 0.3048)
			(end -0.67945 -0.305054)
			(stroke
				(width 0.1)
				(type default)
			)
			(layer "F.Fab")
		)
		(fp_line
			(start -0.12065 0.3048)
			(end -0.67945 0.3048)
			(stroke
				(width 0.1)
				(type default)
			)
			(layer "F.Fab")
		)
		(fp_line
			(start 0.120396 0.3048)
			(end 0.120396 0.2794)
			(stroke
				(width 0.1)
				(type default)
			)
			(layer "F.Fab")
		)
		(fp_line
			(start 0.67945 0.3048)
			(end 0.120396 0.3048)
			(stroke
				(width 0.1)
				(type default)
			)
			(layer "F.Fab")
		)
		(fp_line
			(start -0.12065 0.2794)
			(end -0.12065 0.3048)
			(stroke
				(width 0.1)
				(type default)
			)
			(layer "F.Fab")
		)
		(fp_line
			(start 0.120396 0.2794)
			(end -0.12065 0.2794)
			(stroke
				(width 0.1)
				(type default)
			)
			(layer "F.Fab")
		)
		(fp_line
			(start -0.12065 -0.2794)
			(end 0.12065 -0.2794)
			(stroke
				(width 0.1)
				(type default)
			)
			(layer "F.Fab")
		)
		(fp_line
			(start 0.12065 -0.2794)
			(end 0.12065 -0.3048)
			(stroke
				(width 0.1)
				(type default)
			)
			(layer "F.Fab")
		)
		(fp_line
			(start 0.12065 -0.3048)
			(end 0.67945 -0.3048)
			(stroke
				(width 0.1)
				(type default)
			)
			(layer "F.Fab")
		)
		(fp_line
			(start 0.67945 -0.3048)
			(end 0.67945 0.3048)
			(stroke
				(width 0.1)
				(type default)
			)
			(layer "F.Fab")
		)
		(fp_line
			(start -0.67945 -0.305054)
			(end -0.12065 -0.305054)
			(stroke
				(width 0.1)
				(type default)
			)
			(layer "F.Fab")
		)
		(fp_line
			(start -0.12065 -0.305054)
			(end -0.12065 -0.2794)
			(stroke
				(width 0.1)
				(type default)
			)
			(layer "F.Fab")
		)
		(pad "1" smd circle
			(at -0.40005 0 270)
			(size 0 0)
			(layers "F.Cu" "F.Mask" "F.Paste")
			(net "RST_SSD8_PERST_N")
		)
		(pad "2" smd circle
			(at 0.40005 0 270)
			(size 0 0)
			(layers "F.Cu" "F.Mask" "F.Paste")
			(net "RST_SSD8_PERST_R_N")
		)
	)
	(footprint ""
		(layer "F.Cu")
		(at 109.347 -37.47516)
		(property "Reference" "R6062"
			(at 0 0 0)
			(layer "F.SilkS")
			(hide yes)
			(effects
				(font
					(size 1.27 1.27)
				)
			)
		)
		(property "Value" ""
			(at 0 0 0)
			(layer "F.Fab")
			(effects
				(font
					(size 1.27 1.27)
				)
			)
		)
		(duplicate_pad_numbers_are_jumpers no)
		(fp_line
			(start -0.7874 -0.4064)
			(end 0.7874 -0.4064)
			(stroke
				(width 0.1524)
				(type default)
			)
			(layer "F.SilkS")
		)
		(fp_line
			(start -0.7874 0.4064)
			(end -0.7874 -0.4064)
			(stroke
				(width 0.1524)
				(type default)
			)
			(layer "F.SilkS")
		)
		(fp_line
			(start 0.7874 -0.4064)
			(end 0.7874 0.4064)
			(stroke
				(width 0.1524)
				(type default)
			)
			(layer "F.SilkS")
		)
		(fp_line
			(start 0.7874 0.4064)
			(end -0.7874 0.4064)
			(stroke
				(width 0.1524)
				(type default)
			)
			(layer "F.SilkS")
		)
		(fp_line
			(start -0.67945 -0.305054)
			(end -0.12065 -0.305054)
			(stroke
				(width 0.1)
				(type default)
			)
			(layer "F.Fab")
		)
		(fp_line
			(start -0.67945 0.3048)
			(end -0.67945 -0.305054)
			(stroke
				(width 0.1)
				(type default)
			)
			(layer "F.Fab")
		)
		(fp_line
			(start -0.12065 -0.305054)
			(end -0.12065 -0.2794)
			(stroke
				(width 0.1)
				(type default)
			)
			(layer "F.Fab")
		)
		(fp_line
			(start -0.12065 -0.2794)
			(end 0.12065 -0.2794)
			(stroke
				(width 0.1)
				(type default)
			)
			(layer "F.Fab")
		)
		(fp_line
			(start -0.12065 0.2794)
			(end -0.12065 0.3048)
			(stroke
				(width 0.1)
				(type default)
			)
			(layer "F.Fab")
		)
		(fp_line
			(start -0.12065 0.3048)
			(end -0.67945 0.3048)
			(stroke
				(width 0.1)
				(type default)
			)
			(layer "F.Fab")
		)
		(fp_line
			(start 0.120396 0.2794)
			(end -0.12065 0.2794)
			(stroke
				(width 0.1)
				(type default)
			)
			(layer "F.Fab")
		)
		(fp_line
			(start 0.120396 0.3048)
			(end 0.120396 0.2794)
			(stroke
				(width 0.1)
				(type default)
			)
			(layer "F.Fab")
		)
		(fp_line
			(start 0.12065 -0.3048)
			(end 0.67945 -0.3048)
			(stroke
				(width 0.1)
				(type default)
			)
			(layer "F.Fab")
		)
		(fp_line
			(start 0.12065 -0.2794)
			(end 0.12065 -0.3048)
			(stroke
				(width 0.1)
				(type default)
			)
			(layer "F.Fab")
		)
		(fp_line
			(start 0.67945 -0.3048)
			(end 0.67945 0.3048)
			(stroke
				(width 0.1)
				(type default)
			)
			(layer "F.Fab")
		)
		(fp_line
			(start 0.67945 0.3048)
			(end 0.120396 0.3048)
			(stroke
				(width 0.1)
				(type default)
			)
			(layer "F.Fab")
		)
		(pad "1" smd circle
			(at -0.40005 0)
			(size 0 0)
			(layers "F.Cu" "F.Mask" "F.Paste")
			(net "P3V3_SSD4")
		)
		(pad "2" smd circle
			(at 0.40005 0)
			(size 0 0)
			(layers "F.Cu" "F.Mask" "F.Paste")
			(net "P3V3_SSD4_PG_G1")
		)
	)
	(footprint ""
		(layer "F.Cu")
		(at 376.809 -179.451)
		(property "Reference" "R4719"
			(at 0 0 0)
			(layer "F.SilkS")
			(hide yes)
			(effects
				(font
					(size 1.27 1.27)
				)
			)
		)
		(property "Value" ""
			(at 0 0 0)
			(layer "F.Fab")
			(effects
				(font
					(size 1.27 1.27)
				)
			)
		)
		(duplicate_pad_numbers_are_jumpers no)
		(fp_line
			(start -0.7874 -0.4064)
			(end 0.7874 -0.4064)
			(stroke
				(width 0.1524)
				(type default)
			)
			(layer "F.SilkS")
		)
		(fp_line
			(start -0.7874 0.4064)
			(end -0.7874 -0.4064)
			(stroke
				(width 0.1524)
				(type default)
			)
			(layer "F.SilkS")
		)
		(fp_line
			(start 0.7874 -0.4064)
			(end 0.7874 0.4064)
			(stroke
				(width 0.1524)
				(type default)
			)
			(layer "F.SilkS")
		)
		(fp_line
			(start 0.7874 0.4064)
			(end -0.7874 0.4064)
			(stroke
				(width 0.1524)
				(type default)
			)
			(layer "F.SilkS")
		)
		(fp_line
			(start -0.67945 -0.305054)
			(end -0.12065 -0.305054)
			(stroke
				(width 0.1)
				(type default)
			)
			(layer "F.Fab")
		)
		(fp_line
			(start -0.67945 0.3048)
			(end -0.67945 -0.305054)
			(stroke
				(width 0.1)
				(type default)
			)
			(layer "F.Fab")
		)
		(fp_line
			(start -0.12065 -0.305054)
			(end -0.12065 -0.2794)
			(stroke
				(width 0.1)
				(type default)
			)
			(layer "F.Fab")
		)
		(fp_line
			(start -0.12065 -0.2794)
			(end 0.12065 -0.2794)
			(stroke
				(width 0.1)
				(type default)
			)
			(layer "F.Fab")
		)
		(fp_line
			(start -0.12065 0.2794)
			(end -0.12065 0.3048)
			(stroke
				(width 0.1)
				(type default)
			)
			(layer "F.Fab")
		)
		(fp_line
			(start -0.12065 0.3048)
			(end -0.67945 0.3048)
			(stroke
				(width 0.1)
				(type default)
			)
			(layer "F.Fab")
		)
		(fp_line
			(start 0.120396 0.2794)
			(end -0.12065 0.2794)
			(stroke
				(width 0.1)
				(type default)
			)
			(layer "F.Fab")
		)
		(fp_line
			(start 0.120396 0.3048)
			(end 0.120396 0.2794)
			(stroke
				(width 0.1)
				(type default)
			)
			(layer "F.Fab")
		)
		(fp_line
			(start 0.12065 -0.3048)
			(end 0.67945 -0.3048)
			(stroke
				(width 0.1)
				(type default)
			)
			(layer "F.Fab")
		)
		(fp_line
			(start 0.12065 -0.2794)
			(end 0.12065 -0.3048)
			(stroke
				(width 0.1)
				(type default)
			)
			(layer "F.Fab")
		)
		(fp_line
			(start 0.67945 -0.3048)
			(end 0.67945 0.3048)
			(stroke
				(width 0.1)
				(type default)
			)
			(layer "F.Fab")
		)
		(fp_line
			(start 0.67945 0.3048)
			(end 0.120396 0.3048)
			(stroke
				(width 0.1)
				(type default)
			)
			(layer "F.Fab")
		)
		(pad "1" smd circle
			(at -0.40005 0)
			(size 0 0)
			(layers "F.Cu" "F.Mask" "F.Paste")
			(net "GND")
		)
		(pad "2" smd circle
			(at 0.40005 0)
			(size 0 0)
			(layers "F.Cu" "F.Mask" "F.Paste")
			(net "PCA9555_1_PEX1_A0")
		)
	)
)
